(kicad_pcb
	(version 20221018)
	(generator pcbnew)
	(general
    (thickness 1.62)
  )
	(paper "A4")
	(title_block
    (title "ECP5 - Datacenter Secure Control Module (DC-SCM)")
    (date "2024-07-01")
    (rev "1.2.1")
		(comment 9 "footprints 312-319 of 506")
	)
	(layers
    (0 "F.Cu" signal)
    (1 "In1.Cu" power)
    (2 "In2.Cu" signal)
    (3 "In3.Cu" power)
    (4 "In4.Cu" power)
    (5 "In5.Cu" signal)
    (6 "In6.Cu" power)
    (31 "B.Cu" signal)
    (32 "B.Adhes" user "B.Adhesive")
    (33 "F.Adhes" user "F.Adhesive")
    (34 "B.Paste" user)
    (35 "F.Paste" user)
    (36 "B.SilkS" user "B.Silkscreen")
    (37 "F.SilkS" user "F.Silkscreen")
    (38 "B.Mask" user)
    (39 "F.Mask" user)
    (40 "Dwgs.User" user "User.Drawings")
    (41 "Cmts.User" user "User.Comments")
    (42 "Eco1.User" user "User.Eco1")
    (43 "Eco2.User" user "User.Eco2")
    (44 "Edge.Cuts" user)
    (45 "Margin" user)
    (46 "B.CrtYd" user "B.Courtyard")
    (47 "F.CrtYd" user "F.Courtyard")
    (48 "B.Fab" user)
    (49 "F.Fab" user)
  )
	(footprint "antmicro-footprints:C_0402_1005Metric" (layer "B.Cu")
    (at 103.55 117.05 -90)
    (descr "Capacitor SMD 0402")
    (tags "capacitor SMD 0402")
    (property "Author" "Antmicro")
    (property "Dielectric" "")
    (property "License" "Apache-2.0")
    (property "MPN" "C1005X5R1E474M050BB")
    (property "Manufacturer" "TDK")
    (property "Public" "False")
    (property "Sheetfile" "fpga-power-supply.kicad_sch")
    (property "Sheetname" "FPGA power supply")
    (property "Val" "470n")
    (property "Voltage" "")
    (property "ki_description" "SMD Multilayer Ceramic Capacitor, 0.47 µF, 25 V, 0402 [1005 Metric], ± 20%, X5R, C")
    (property "ki_keywords" "0402, SMT, CAPACITOR, PASSIVE, CERAMIC, MLCC")
    (attr smd)
    (fp_text reference "C192" (at 22.65 0.05 90) (layer "B.SilkS")
        (effects (font (size 0.7 0.7) (thickness 0.127)) (justify mirror))
    )
    (fp_text value "C_470n_0402" (at 0 -1.17 90) (layer "B.Fab")
        (effects (font (size 1 1) (thickness 0.15)) (justify mirror))
    )
    (fp_text user "${REFERENCE}" (at 0 0 90) (layer "B.Fab")
        (effects (font (size 0.25 0.25) (thickness 0.04)) (justify mirror))
    )
    (fp_text user "License: Apache-2.0" (at -0.939 -5.799 90) (layer "B.Fab") hide
        (effects (font (size 0.7 0.7) (thickness 0.15)) (justify left bottom mirror))
    )
    (fp_text user "Author: Antmicro" (at -0.939 -3.399 90) (layer "B.Fab") hide
        (effects (font (size 0.7 0.7) (thickness 0.15)) (justify left bottom mirror))
    )
    (fp_rect (start -0.925 0.47) (end 0.925 -0.47)
      (stroke (width 0.05) (type default)) (fill none) (layer "B.CrtYd"))
    (fp_line (start -0.494 -0.248) (end -0.494 0.25)
      (stroke (width 0.15) (type solid)) (layer "B.Fab"))
    (fp_line (start -0.494 0.25) (end 0.504 0.25)
      (stroke (width 0.15) (type solid)) (layer "B.Fab"))
    (fp_line (start 0.504 -0.248) (end -0.494 -0.248)
      (stroke (width 0.15) (type solid)) (layer "B.Fab"))
    (fp_line (start 0.504 0.25) (end 0.504 -0.248)
      (stroke (width 0.15) (type solid)) (layer "B.Fab"))
    (pad "1" smd roundrect (at -0.48 0 270) (size 0.59 0.64) (layers "B.Cu" "B.Paste" "B.Mask") (roundrect_rratio 0.25)
      (net 211 "VCC1V2") (pintype "passive"))
    (pad "2" smd roundrect (at 0.48 0 270) (size 0.59 0.64) (layers "B.Cu" "B.Paste" "B.Mask") (roundrect_rratio 0.25)
      (net 1 "GND") (pintype "passive"))
  )
	(footprint "antmicro-footprints:C_0402_1005Metric" (layer "B.Cu")
    (at 100.5 117 90)
    (descr "Capacitor SMD 0402")
    (tags "capacitor SMD 0402")
    (property "Author" "Antmicro")
    (property "Dielectric" "")
    (property "License" "Apache-2.0")
    (property "MPN" "C1005X5R1E474M050BB")
    (property "Manufacturer" "TDK")
    (property "Public" "False")
    (property "Sheetfile" "fpga-power-supply.kicad_sch")
    (property "Sheetname" "FPGA power supply")
    (property "Val" "470n")
    (property "Voltage" "")
    (property "ki_description" "SMD Multilayer Ceramic Capacitor, 0.47 µF, 25 V, 0402 [1005 Metric], ± 20%, X5R, C")
    (property "ki_keywords" "0402, SMT, CAPACITOR, PASSIVE, CERAMIC, MLCC")
    (attr smd)
    (fp_text reference "C193" (at -22.7 -0.05 90) (layer "B.SilkS")
        (effects (font (size 0.7 0.7) (thickness 0.127)) (justify mirror))
    )
    (fp_text value "C_470n_0402" (at 0 -1.17 90) (layer "B.Fab")
        (effects (font (size 1 1) (thickness 0.15)) (justify mirror))
    )
    (fp_text user "Author: Antmicro" (at -0.939 -3.399 270) (layer "B.Fab") hide
        (effects (font (size 0.7 0.7) (thickness 0.15)) (justify left bottom mirror))
    )
    (fp_text user "${REFERENCE}" (at 0 0 90) (layer "B.Fab")
        (effects (font (size 0.25 0.25) (thickness 0.04)) (justify mirror))
    )
    (fp_text user "License: Apache-2.0" (at -0.939 -5.799 270) (layer "B.Fab") hide
        (effects (font (size 0.7 0.7) (thickness 0.15)) (justify left bottom mirror))
    )
    (fp_rect (start -0.925 0.47) (end 0.925 -0.47)
      (stroke (width 0.05) (type default)) (fill none) (layer "B.CrtYd"))
    (fp_line (start -0.494 -0.248) (end -0.494 0.25)
      (stroke (width 0.15) (type solid)) (layer "B.Fab"))
    (fp_line (start -0.494 0.25) (end 0.504 0.25)
      (stroke (width 0.15) (type solid)) (layer "B.Fab"))
    (fp_line (start 0.504 -0.248) (end -0.494 -0.248)
      (stroke (width 0.15) (type solid)) (layer "B.Fab"))
    (fp_line (start 0.504 0.25) (end 0.504 -0.248)
      (stroke (width 0.15) (type solid)) (layer "B.Fab"))
    (pad "1" smd roundrect (at -0.48 0 90) (size 0.59 0.64) (layers "B.Cu" "B.Paste" "B.Mask") (roundrect_rratio 0.25)
      (net 211 "VCC1V2") (pintype "passive"))
    (pad "2" smd roundrect (at 0.48 0 90) (size 0.59 0.64) (layers "B.Cu" "B.Paste" "B.Mask") (roundrect_rratio 0.25)
      (net 1 "GND") (pintype "passive"))
  )
	(footprint "antmicro-footprints:C_0402_1005Metric" (layer "B.Cu")
    (at 99.25 115.05 180)
    (descr "Capacitor SMD 0402")
    (tags "capacitor SMD 0402")
    (property "Author" "Antmicro")
    (property "Dielectric" "")
    (property "License" "Apache-2.0")
    (property "MPN" "GRM155R61A475MEAAD")
    (property "Manufacturer" "Murata")
    (property "Public" "False")
    (property "Sheetfile" "fpga-banks.kicad_sch")
    (property "Sheetname" "FPGA banks")
    (property "Val" "4u7")
    (property "Voltage" "")
    (property "ki_description" "SMD Multilayer Ceramic Capacitor, 4.7 µF, 10 V, 0402 [1005 Metric], ± 20%, X5R, GRM Series")
    (property "ki_keywords" "0402, SMT, CAPACITOR, PASSIVE")
    (attr smd)
    (fp_text reference "C203" (at 2.35 0.2) (layer "B.SilkS")
        (effects (font (size 0.7 0.7) (thickness 0.127)) (justify mirror))
    )
    (fp_text value "C_4u7_0402" (at 0 -1.17) (layer "B.Fab")
        (effects (font (size 1 1) (thickness 0.15)) (justify mirror))
    )
    (fp_text user "Author: Antmicro" (at -0.939 -3.399) (layer "B.Fab") hide
        (effects (font (size 0.7 0.7) (thickness 0.15)) (justify left bottom mirror))
    )
    (fp_text user "${REFERENCE}" (at 0 0) (layer "B.Fab")
        (effects (font (size 0.25 0.25) (thickness 0.04)) (justify mirror))
    )
    (fp_text user "License: Apache-2.0" (at -0.939 -5.799) (layer "B.Fab") hide
        (effects (font (size 0.7 0.7) (thickness 0.15)) (justify left bottom mirror))
    )
    (fp_rect (start -0.925 0.47) (end 0.925 -0.47)
      (stroke (width 0.05) (type default)) (fill none) (layer "B.CrtYd"))
    (fp_line (start -0.494 -0.248) (end -0.494 0.25)
      (stroke (width 0.15) (type solid)) (layer "B.Fab"))
    (fp_line (start -0.494 0.25) (end 0.504 0.25)
      (stroke (width 0.15) (type solid)) (layer "B.Fab"))
    (fp_line (start 0.504 -0.248) (end -0.494 -0.248)
      (stroke (width 0.15) (type solid)) (layer "B.Fab"))
    (fp_line (start 0.504 0.25) (end 0.504 -0.248)
      (stroke (width 0.15) (type solid)) (layer "B.Fab"))
    (pad "1" smd roundrect (at -0.48 0 180) (size 0.59 0.64) (layers "B.Cu" "B.Paste" "B.Mask") (roundrect_rratio 0.25)
      (net 2 "VCC3V3") (pintype "passive"))
    (pad "2" smd roundrect (at 0.48 0 180) (size 0.59 0.64) (layers "B.Cu" "B.Paste" "B.Mask") (roundrect_rratio 0.25)
      (net 1 "GND") (pintype "passive"))
  )
	(footprint "antmicro-footprints:C_0402_1005Metric" (layer "B.Cu")
    (at 104.4 115.15 -90)
    (descr "Capacitor SMD 0402")
    (tags "capacitor SMD 0402")
    (property "Author" "Antmicro")
    (property "Dielectric" "")
    (property "License" "Apache-2.0")
    (property "MPN" "C1005X5R1E474M050BB")
    (property "Manufacturer" "TDK")
    (property "Public" "False")
    (property "Sheetfile" "fpga-banks.kicad_sch")
    (property "Sheetname" "FPGA banks")
    (property "Val" "470n")
    (property "Voltage" "")
    (property "ki_description" "SMD Multilayer Ceramic Capacitor, 0.47 µF, 25 V, 0402 [1005 Metric], ± 20%, X5R, C")
    (property "ki_keywords" "0402, SMT, CAPACITOR, PASSIVE, CERAMIC, MLCC")
    (attr smd)
    (fp_text reference "C204" (at -4.35 -0.05 90) (layer "B.SilkS")
        (effects (font (size 0.7 0.7) (thickness 0.127)) (justify mirror))
    )
    (fp_text value "C_470n_0402" (at 0 -1.17 90) (layer "B.Fab")
        (effects (font (size 1 1) (thickness 0.15)) (justify mirror))
    )
    (fp_text user "${REFERENCE}" (at 0 0 90) (layer "B.Fab")
        (effects (font (size 0.25 0.25) (thickness 0.04)) (justify mirror))
    )
    (fp_text user "Author: Antmicro" (at -0.939 -3.399 90) (layer "B.Fab") hide
        (effects (font (size 0.7 0.7) (thickness 0.15)) (justify left bottom mirror))
    )
    (fp_text user "License: Apache-2.0" (at -0.939 -5.799 90) (layer "B.Fab") hide
        (effects (font (size 0.7 0.7) (thickness 0.15)) (justify left bottom mirror))
    )
    (fp_rect (start -0.925 0.47) (end 0.925 -0.47)
      (stroke (width 0.05) (type default)) (fill none) (layer "B.CrtYd"))
    (fp_line (start -0.494 -0.248) (end -0.494 0.25)
      (stroke (width 0.15) (type solid)) (layer "B.Fab"))
    (fp_line (start -0.494 0.25) (end 0.504 0.25)
      (stroke (width 0.15) (type solid)) (layer "B.Fab"))
    (fp_line (start 0.504 -0.248) (end -0.494 -0.248)
      (stroke (width 0.15) (type solid)) (layer "B.Fab"))
    (fp_line (start 0.504 0.25) (end 0.504 -0.248)
      (stroke (width 0.15) (type solid)) (layer "B.Fab"))
    (pad "1" smd roundrect (at -0.48 0 270) (size 0.59 0.64) (layers "B.Cu" "B.Paste" "B.Mask") (roundrect_rratio 0.25)
      (net 2 "VCC3V3") (pintype "passive"))
    (pad "2" smd roundrect (at 0.48 0 270) (size 0.59 0.64) (layers "B.Cu" "B.Paste" "B.Mask") (roundrect_rratio 0.25)
      (net 1 "GND") (pintype "passive"))
  )
	(footprint "antmicro-footprints:C_0402_1005Metric" (layer "B.Cu")
    (at 102.75 113.8 90)
    (descr "Capacitor SMD 0402")
    (tags "capacitor SMD 0402")
    (property "Author" "Antmicro")
    (property "Dielectric" "")
    (property "License" "Apache-2.0")
    (property "MPN" "C1005X5R1E474M050BB")
    (property "Manufacturer" "TDK")
    (property "Public" "False")
    (property "Sheetfile" "fpga-banks.kicad_sch")
    (property "Sheetname" "FPGA banks")
    (property "Val" "470n")
    (property "Voltage" "")
    (property "ki_description" "SMD Multilayer Ceramic Capacitor, 0.47 µF, 25 V, 0402 [1005 Metric], ± 20%, X5R, C")
    (property "ki_keywords" "0402, SMT, CAPACITOR, PASSIVE, CERAMIC, MLCC")
    (attr smd)
    (fp_text reference "C206" (at 2.45 -0.05 90) (layer "B.SilkS")
        (effects (font (size 0.7 0.7) (thickness 0.127)) (justify mirror))
    )
    (fp_text value "C_470n_0402" (at 0 -1.17 90) (layer "B.Fab")
        (effects (font (size 1 1) (thickness 0.15)) (justify mirror))
    )
    (fp_text user "Author: Antmicro" (at -0.939 -3.399 270) (layer "B.Fab") hide
        (effects (font (size 0.7 0.7) (thickness 0.15)) (justify left bottom mirror))
    )
    (fp_text user "License: Apache-2.0" (at -0.939 -5.799 270) (layer "B.Fab") hide
        (effects (font (size 0.7 0.7) (thickness 0.15)) (justify left bottom mirror))
    )
    (fp_text user "${REFERENCE}" (at 0 0 90) (layer "B.Fab")
        (effects (font (size 0.25 0.25) (thickness 0.04)) (justify mirror))
    )
    (fp_rect (start -0.925 0.47) (end 0.925 -0.47)
      (stroke (width 0.05) (type default)) (fill none) (layer "B.CrtYd"))
    (fp_line (start -0.494 -0.248) (end -0.494 0.25)
      (stroke (width 0.15) (type solid)) (layer "B.Fab"))
    (fp_line (start -0.494 0.25) (end 0.504 0.25)
      (stroke (width 0.15) (type solid)) (layer "B.Fab"))
    (fp_line (start 0.504 -0.248) (end -0.494 -0.248)
      (stroke (width 0.15) (type solid)) (layer "B.Fab"))
    (fp_line (start 0.504 0.25) (end 0.504 -0.248)
      (stroke (width 0.15) (type solid)) (layer "B.Fab"))
    (pad "1" smd roundrect (at -0.48 0 90) (size 0.59 0.64) (layers "B.Cu" "B.Paste" "B.Mask") (roundrect_rratio 0.25)
      (net 2 "VCC3V3") (pintype "passive"))
    (pad "2" smd roundrect (at 0.48 0 90) (size 0.59 0.64) (layers "B.Cu" "B.Paste" "B.Mask") (roundrect_rratio 0.25)
      (net 1 "GND") (pintype "passive"))
  )
	(footprint "antmicro-footprints:C_0402_1005Metric" (layer "B.Cu")
    (at 99.25 114.05 180)
    (descr "Capacitor SMD 0402")
    (tags "capacitor SMD 0402")
    (property "Author" "Antmicro")
    (property "Dielectric" "")
    (property "License" "Apache-2.0")
    (property "MPN" "C1005X5R1E474M050BB")
    (property "Manufacturer" "TDK")
    (property "Public" "False")
    (property "Sheetfile" "fpga-banks.kicad_sch")
    (property "Sheetname" "FPGA banks")
    (property "Val" "470n")
    (property "Voltage" "")
    (property "ki_description" "SMD Multilayer Ceramic Capacitor, 0.47 µF, 25 V, 0402 [1005 Metric], ± 20%, X5R, C")
    (property "ki_keywords" "0402, SMT, CAPACITOR, PASSIVE, CERAMIC, MLCC")
    (attr smd)
    (fp_text reference "C207" (at 2.4 0.25) (layer "B.SilkS")
        (effects (font (size 0.7 0.7) (thickness 0.127)) (justify mirror))
    )
    (fp_text value "C_470n_0402" (at 0 -1.17) (layer "B.Fab")
        (effects (font (size 1 1) (thickness 0.15)) (justify mirror))
    )
    (fp_text user "Author: Antmicro" (at -0.939 -3.399) (layer "B.Fab") hide
        (effects (font (size 0.7 0.7) (thickness 0.15)) (justify left bottom mirror))
    )
    (fp_text user "License: Apache-2.0" (at -0.939 -5.799) (layer "B.Fab") hide
        (effects (font (size 0.7 0.7) (thickness 0.15)) (justify left bottom mirror))
    )
    (fp_text user "${REFERENCE}" (at 0 0) (layer "B.Fab")
        (effects (font (size 0.25 0.25) (thickness 0.04)) (justify mirror))
    )
    (fp_rect (start -0.925 0.47) (end 0.925 -0.47)
      (stroke (width 0.05) (type default)) (fill none) (layer "B.CrtYd"))
    (fp_line (start -0.494 -0.248) (end -0.494 0.25)
      (stroke (width 0.15) (type solid)) (layer "B.Fab"))
    (fp_line (start -0.494 0.25) (end 0.504 0.25)
      (stroke (width 0.15) (type solid)) (layer "B.Fab"))
    (fp_line (start 0.504 -0.248) (end -0.494 -0.248)
      (stroke (width 0.15) (type solid)) (layer "B.Fab"))
    (fp_line (start 0.504 0.25) (end 0.504 -0.248)
      (stroke (width 0.15) (type solid)) (layer "B.Fab"))
    (pad "1" smd roundrect (at -0.48 0 180) (size 0.59 0.64) (layers "B.Cu" "B.Paste" "B.Mask") (roundrect_rratio 0.25)
      (net 2 "VCC3V3") (pintype "passive"))
    (pad "2" smd roundrect (at 0.48 0 180) (size 0.59 0.64) (layers "B.Cu" "B.Paste" "B.Mask") (roundrect_rratio 0.25)
      (net 1 "GND") (pintype "passive"))
  )
	(footprint "antmicro-footprints:C_0402_1005Metric" (layer "B.Cu")
    (at 109.55 114.95)
    (descr "Capacitor SMD 0402")
    (tags "capacitor SMD 0402")
    (property "Author" "Antmicro")
    (property "Dielectric" "")
    (property "License" "Apache-2.0")
    (property "MPN" "GRM155R61A475MEAAD")
    (property "Manufacturer" "Murata")
    (property "Public" "False")
    (property "Sheetfile" "fpga-banks.kicad_sch")
    (property "Sheetname" "FPGA banks")
    (property "Val" "4u7")
    (property "Voltage" "")
    (property "ki_description" "SMD Multilayer Ceramic Capacitor, 4.7 µF, 10 V, 0402 [1005 Metric], ± 20%, X5R, GRM Series")
    (property "ki_keywords" "0402, SMT, CAPACITOR, PASSIVE")
    (attr smd)
    (fp_text reference "C209" (at 2.8 -0.05) (layer "B.SilkS")
        (effects (font (size 0.7 0.7) (thickness 0.127)) (justify mirror))
    )
    (fp_text value "C_4u7_0402" (at 0 -1.17) (layer "B.Fab")
        (effects (font (size 1 1) (thickness 0.15)) (justify mirror))
    )
    (fp_text user "${REFERENCE}" (at 0 0) (layer "B.Fab")
        (effects (font (size 0.25 0.25) (thickness 0.04)) (justify mirror))
    )
    (fp_text user "License: Apache-2.0" (at -0.939 -5.799 180) (layer "B.Fab") hide
        (effects (font (size 0.7 0.7) (thickness 0.15)) (justify left bottom mirror))
    )
    (fp_text user "Author: Antmicro" (at -0.939 -3.399 180) (layer "B.Fab") hide
        (effects (font (size 0.7 0.7) (thickness 0.15)) (justify left bottom mirror))
    )
    (fp_rect (start -0.925 0.47) (end 0.925 -0.47)
      (stroke (width 0.05) (type default)) (fill none) (layer "B.CrtYd"))
    (fp_line (start -0.494 -0.248) (end -0.494 0.25)
      (stroke (width 0.15) (type solid)) (layer "B.Fab"))
    (fp_line (start -0.494 0.25) (end 0.504 0.25)
      (stroke (width 0.15) (type solid)) (layer "B.Fab"))
    (fp_line (start 0.504 -0.248) (end -0.494 -0.248)
      (stroke (width 0.15) (type solid)) (layer "B.Fab"))
    (fp_line (start 0.504 0.25) (end 0.504 -0.248)
      (stroke (width 0.15) (type solid)) (layer "B.Fab"))
    (pad "1" smd roundrect (at -0.48 0) (size 0.59 0.64) (layers "B.Cu" "B.Paste" "B.Mask") (roundrect_rratio 0.25)
      (net 2 "VCC3V3") (pintype "passive"))
    (pad "2" smd roundrect (at 0.48 0) (size 0.59 0.64) (layers "B.Cu" "B.Paste" "B.Mask") (roundrect_rratio 0.25)
      (net 1 "GND") (pintype "passive"))
  )
	(footprint "antmicro-footprints:C_0402_1005Metric" (layer "B.Cu")
    (at 111.25 124.775)
    (descr "Capacitor SMD 0402")
    (tags "capacitor SMD 0402")
    (property "Author" "Antmicro")
    (property "Dielectric" "")
    (property "License" "Apache-2.0")
    (property "MPN" "C1005X5R1E474M050BB")
    (property "Manufacturer" "TDK")
    (property "Public" "False")
    (property "Sheetfile" "fpga-banks.kicad_sch")
    (property "Sheetname" "FPGA banks")
    (property "Val" "470n")
    (property "Voltage" "")
    (property "ki_description" "SMD Multilayer Ceramic Capacitor, 0.47 µF, 25 V, 0402 [1005 Metric], ± 20%, X5R, C")
    (property "ki_keywords" "0402, SMT, CAPACITOR, PASSIVE, CERAMIC, MLCC")
    (attr smd)
    (fp_text reference "C210" (at 2.55 -0.025) (layer "B.SilkS")
        (effects (font (size 0.7 0.7) (thickness 0.127)) (justify mirror))
    )
    (fp_text value "C_470n_0402" (at 0 -1.17) (layer "B.Fab")
        (effects (font (size 1 1) (thickness 0.15)) (justify mirror))
    )
    (fp_text user "Author: Antmicro" (at -0.939 -3.399 180) (layer "B.Fab") hide
        (effects (font (size 0.7 0.7) (thickness 0.15)) (justify left bottom mirror))
    )
    (fp_text user "License: Apache-2.0" (at -0.939 -5.799 180) (layer "B.Fab") hide
        (effects (font (size 0.7 0.7) (thickness 0.15)) (justify left bottom mirror))
    )
    (fp_text user "${REFERENCE}" (at 0 0) (layer "B.Fab")
        (effects (font (size 0.25 0.25) (thickness 0.04)) (justify mirror))
    )
    (fp_rect (start -0.925 0.47) (end 0.925 -0.47)
      (stroke (width 0.05) (type default)) (fill none) (layer "B.CrtYd"))
    (fp_line (start -0.494 -0.248) (end -0.494 0.25)
      (stroke (width 0.15) (type solid)) (layer "B.Fab"))
    (fp_line (start -0.494 0.25) (end 0.504 0.25)
      (stroke (width 0.15) (type solid)) (layer "B.Fab"))
    (fp_line (start 0.504 -0.248) (end -0.494 -0.248)
      (stroke (width 0.15) (type solid)) (layer "B.Fab"))
    (fp_line (start 0.504 0.25) (end 0.504 -0.248)
      (stroke (width 0.15) (type solid)) (layer "B.Fab"))
    (pad "1" smd roundrect (at -0.48 0) (size 0.59 0.64) (layers "B.Cu" "B.Paste" "B.Mask") (roundrect_rratio 0.25)
      (net 2 "VCC3V3") (pintype "passive"))
    (pad "2" smd roundrect (at 0.48 0) (size 0.59 0.64) (layers "B.Cu" "B.Paste" "B.Mask") (roundrect_rratio 0.25)
      (net 1 "GND") (pintype "passive"))
  )
)
